# T6G (Grand Teton) — schematic netlist excerpt (pin names and nets, part order shuffled) for the footprints in the layout excerpt that follows; sources: Cadence DE-HDL packaged netlist, KiCad conversion of 04192023_DAF0TMB3IC0_F0TG_MB_C_brd_V02_OCP.brd

C71  Q_CAP  4.7PF 50V 0.1P NPO  pkg C0402  page 233 : A = CLK_GEN2_XTAL_IN_R ; B = GND
C6570  Q_CAP_DIFFBUS  DIFF BUS_0.22UF 6.3V 20% X6S  pkg C0201  page 297 : \1\ = P5E_CPU0_P2_TX_BUF_C_DN<2> ; \2\ = P5E_CPU0_P2_TX_BUF_DN<2>
C686  Q_CAP_DIFFBUS  DIFF BUS_0.22UF 6.3V 20% X6S  pkg C0201  page 67 : \1\ = P5E_CPU1_G1_TX_C_DN<11> ; \2\ = P5E_CPU1_G1_TX_DN<11>

(kicad_pcb
	(version 20260206)
	(generator "pcbnew")
	(generator_version "10.0")
	(general
		(thickness 1.6)
		(legacy_teardrops no)
	)
	(paper "A4")
	(title_block
		(title "04192023_DAF0TMB3IC0_F0TG_MB_C_brd_V02_OCP.brd")
		(comment 1 "Grand Teton / footprints 3001-3003 of 8354")
	)
	(layers
		(0 "F.Cu" signal "TOP")
		(4 "In1.Cu" signal "GND")
		(6 "In2.Cu" signal "IN1")
		(8 "In3.Cu" signal "GND1")
		(10 "In4.Cu" signal "IN2")
		(12 "In5.Cu" signal "GND2")
		(14 "In6.Cu" signal "IN3")
		(16 "In7.Cu" signal "GND3")
		(18 "In8.Cu" signal "VCC")
		(20 "In9.Cu" signal "VCC1")
		(22 "In10.Cu" signal "GND4")
		(24 "In11.Cu" signal "IN4")
		(26 "In12.Cu" signal "GND5")
		(28 "In13.Cu" signal "IN5")
		(30 "In14.Cu" signal "GND6")
		(32 "In15.Cu" signal "IN6")
		(34 "In16.Cu" signal "GND7")
		(2 "B.Cu" signal "BOTTOM")
		(9 "F.Adhes" user "F.Adhesive")
		(11 "B.Adhes" user "B.Adhesive")
		(13 "F.Paste" user "Package Geometry/Pastemask Top")
		(15 "B.Paste" user "Package Geometry/Pastemask Bottom")
		(5 "F.SilkS" user "Ref Des/Silkscreen Top")
		(7 "B.SilkS" user "Ref Des/Silkscreen Bottom")
		(1 "F.Mask" user "Board Geometry/Soldermask Top")
		(3 "B.Mask" user "Board Geometry/Soldermask Bottom")
		(17 "Dwgs.User" user "User.Drawings")
		(19 "Cmts.User" user "User.Comments")
		(21 "Eco1.User" user "User.Eco1")
		(23 "Eco2.User" user "User.Eco2")
		(25 "Edge.Cuts" user "Board Geometry/Outline")
		(27 "Margin" user)
		(31 "F.CrtYd" user "Package Geometry/Place Bound Top")
		(29 "B.CrtYd" user "Package Geometry/Place Bound Bottom")
		(35 "F.Fab" user "Ref Des/Assembly Top")
		(33 "B.Fab" user "Ref Des/Assembly Bottom")
	)
	(footprint ""
		(layer "F.Cu")
		(at 376.995182 -416.899344 -90)
		(property "Reference" "C6570"
			(at 0 0 270)
			(layer "F.SilkS")
			(hide yes)
			(effects
				(font
					(size 1.27 1.27)
				)
			)
		)
		(property "Value" ""
			(at 0 0 270)
			(layer "F.Fab")
			(effects
				(font
					(size 1.27 1.27)
				)
			)
		)
		(duplicate_pad_numbers_are_jumpers no)
		(fp_line
			(start -0.299974 0.150114)
			(end -0.299974 -0.150114)
			(stroke
				(width 0.1)
				(type default)
			)
			(layer "F.Fab")
		)
		(fp_line
			(start 0.299974 0.150114)
			(end -0.299974 0.150114)
			(stroke
				(width 0.1)
				(type default)
			)
			(layer "F.Fab")
		)
		(fp_line
			(start -0.299974 -0.150114)
			(end 0.299974 -0.150114)
			(stroke
				(width 0.1)
				(type default)
			)
			(layer "F.Fab")
		)
		(fp_line
			(start 0.299974 -0.150114)
			(end 0.299974 0.150114)
			(stroke
				(width 0.1)
				(type default)
			)
			(layer "F.Fab")
		)
		(pad "1" smd rect
			(at -0.2667 0 270)
			(size 0.3048 0.381)
			(layers "F.Cu" "F.Mask" "F.Paste")
			(net "P5E_CPU0_P2_TX_BUF_C_DN<2>")
		)
		(pad "2" smd rect
			(at 0.2667 0 270)
			(size 0.3048 0.381)
			(layers "F.Cu" "F.Mask" "F.Paste")
			(net "P5E_CPU0_P2_TX_BUF_DN<2>")
		)
	)
	(footprint ""
		(layer "F.Cu")
		(at 26.684478 -16.099536 90)
		(property "Reference" "C686"
			(at 0 0 90)
			(layer "F.SilkS")
			(hide yes)
			(effects
				(font
					(size 1.27 1.27)
				)
			)
		)
		(property "Value" ""
			(at 0 0 90)
			(layer "F.Fab")
			(effects
				(font
					(size 1.27 1.27)
				)
			)
		)
		(duplicate_pad_numbers_are_jumpers no)
		(fp_line
			(start 0.299974 -0.150114)
			(end 0.299974 0.150114)
			(stroke
				(width 0.1)
				(type default)
			)
			(layer "F.Fab")
		)
		(fp_line
			(start -0.299974 -0.150114)
			(end 0.299974 -0.150114)
			(stroke
				(width 0.1)
				(type default)
			)
			(layer "F.Fab")
		)
		(fp_line
			(start 0.299974 0.150114)
			(end -0.299974 0.150114)
			(stroke
				(width 0.1)
				(type default)
			)
			(layer "F.Fab")
		)
		(fp_line
			(start -0.299974 0.150114)
			(end -0.299974 -0.150114)
			(stroke
				(width 0.1)
				(type default)
			)
			(layer "F.Fab")
		)
		(pad "1" smd rect
			(at -0.2667 0 90)
			(size 0.3048 0.381)
			(layers "F.Cu" "F.Mask" "F.Paste")
			(net "P5E_CPU1_G1_TX_C_DN<11>")
		)
		(pad "2" smd rect
			(at 0.2667 0 90)
			(size 0.3048 0.381)
			(layers "F.Cu" "F.Mask" "F.Paste")
			(net "P5E_CPU1_G1_TX_DN<11>")
		)
	)
	(footprint ""
		(layer "F.Cu")
		(at 8.343138 -136.15416 90)
		(property "Reference" "C71"
			(at 0 0 90)
			(layer "F.SilkS")
			(hide yes)
			(effects
				(font
					(size 1.27 1.27)
				)
			)
		)
		(property "Value" ""
			(at 0 0 90)
			(layer "F.Fab")
			(effects
				(font
					(size 1.27 1.27)
				)
			)
		)
		(duplicate_pad_numbers_are_jumpers no)
		(fp_line
			(start 0.7874 -0.4064)
			(end 0.7874 0.4064)
			(stroke
				(width 0.1524)
				(type default)
			)
			(layer "F.SilkS")
		)
		(fp_line
			(start -0.7874 -0.4064)
			(end 0.7874 -0.4064)
			(stroke
				(width 0.1524)
				(type default)
			)
			(layer "F.SilkS")
		)
		(fp_line
			(start 0.7874 0.4064)
			(end -0.7874 0.4064)
			(stroke
				(width 0.1524)
				(type default)
			)
			(layer "F.SilkS")
		)
		(fp_line
			(start -0.7874 0.4064)
			(end -0.7874 -0.4064)
			(stroke
				(width 0.1524)
				(type default)
			)
			(layer "F.SilkS")
		)
		(fp_line
			(start -0.12065 -0.305054)
			(end -0.12065 -0.2794)
			(stroke
				(width 0.1)
				(type default)
			)
			(layer "F.Fab")
		)
		(fp_line
			(start -0.67945 -0.305054)
			(end -0.12065 -0.305054)
			(stroke
				(width 0.1)
				(type default)
			)
			(layer "F.Fab")
		)
		(fp_line
			(start 0.67945 -0.3048)
			(end 0.67945 0.3048)
			(stroke
				(width 0.1)
				(type default)
			)
			(layer "F.Fab")
		)
		(fp_line
			(start 0.12065 -0.3048)
			(end 0.67945 -0.3048)
			(stroke
				(width 0.1)
				(type default)
			)
			(layer "F.Fab")
		)
		(fp_line
			(start 0.12065 -0.2794)
			(end 0.12065 -0.3048)
			(stroke
				(width 0.1)
				(type default)
			)
			(layer "F.Fab")
		)
		(fp_line
			(start -0.12065 -0.2794)
			(end 0.12065 -0.2794)
			(stroke
				(width 0.1)
				(type default)
			)
			(layer "F.Fab")
		)
		(fp_line
			(start 0.120396 0.2794)
			(end -0.12065 0.2794)
			(stroke
				(width 0.1)
				(type default)
			)
			(layer "F.Fab")
		)
		(fp_line
			(start -0.12065 0.2794)
			(end -0.12065 0.3048)
			(stroke
				(width 0.1)
				(type default)
			)
			(layer "F.Fab")
		)
		(fp_line
			(start 0.67945 0.3048)
			(end 0.120396 0.3048)
			(stroke
				(width 0.1)
				(type default)
			)
			(layer "F.Fab")
		)
		(fp_line
			(start 0.120396 0.3048)
			(end 0.120396 0.2794)
			(stroke
				(width 0.1)
				(type default)
			)
			(layer "F.Fab")
		)
		(fp_line
			(start -0.12065 0.3048)
			(end -0.67945 0.3048)
			(stroke
				(width 0.1)
				(type default)
			)
			(layer "F.Fab")
		)
		(fp_line
			(start -0.67945 0.3048)
			(end -0.67945 -0.305054)
			(stroke
				(width 0.1)
				(type default)
			)
			(layer "F.Fab")
		)
		(pad "1" smd circle
			(at -0.40005 0 90)
			(size 0 0)
			(layers "F.Cu" "F.Mask" "F.Paste")
			(net "CLK_GEN2_XTAL_IN_R")
		)
		(pad "2" smd circle
			(at 0.40005 0 90)
			(size 0 0)
			(layers "F.Cu" "F.Mask" "F.Paste")
			(net "GND")
		)
	)
)
